(kicad_pcb
	(version 20241229)
	(generator "pcbnew")
	(generator_version "9.0")
	(general
		(thickness 1.6642)
		(legacy_teardrops no)
	)
	(paper "A3")
	(title_block
		(title "PolarFire SoM")
		(date "2025-07-22")
		(rev "1.1.4")
		(company "Antmicro Ltd")
		(comment 1 "www.antmicro.com")
		(comment 9 "footprints 229-233 of 470")
	)
	(layers
		(0 "F.Cu" mixed)
		(4 "In1.Cu" power)
		(6 "In2.Cu" signal)
		(8 "In3.Cu" power)
		(10 "In4.Cu" signal)
		(12 "In5.Cu" power)
		(14 "In6.Cu" power)
		(16 "In7.Cu" signal)
		(18 "In8.Cu" power)
		(20 "In9.Cu" signal)
		(22 "In10.Cu" power)
		(24 "In11.Cu" signal)
		(26 "In12.Cu" signal)
		(2 "B.Cu" mixed)
		(9 "F.Adhes" user "F.Adhesive")
		(11 "B.Adhes" user "B.Adhesive")
		(13 "F.Paste" user)
		(15 "B.Paste" user)
		(5 "F.SilkS" user "F.Silkscreen")
		(7 "B.SilkS" user "B.Silkscreen")
		(1 "F.Mask" user)
		(3 "B.Mask" user)
		(17 "Dwgs.User" user "User.Drawings")
		(19 "Cmts.User" user "User.Comments")
		(21 "Eco1.User" user "User.Eco1")
		(23 "Eco2.User" user "User.Eco2")
		(25 "Edge.Cuts" user)
		(27 "Margin" user)
		(31 "F.CrtYd" user "F.Courtyard")
		(29 "B.CrtYd" user "B.Courtyard")
		(35 "F.Fab" user)
		(33 "B.Fab" user)
	)
	(footprint "antmicro-footprints:R_0402_1005Metric"
		(layer "B.Cu")
		(at 222.13 128.2 180)
		(descr "Resistor SMD 0402")
		(tags "resistor SMD 0402")
		(property "Reference" "R72"
			(at -1.82 0.45 0)
			(layer "B.SilkS")
			(effects
				(font
					(size 0.7 0.7)
					(thickness 0.15)
				)
				(justify left bottom mirror)
			)
		)
		(property "Value" "R_470R_0402"
			(at -1.011843 -1.772047 0)
			(layer "B.Fab")
			(hide yes)
			(effects
				(font
					(size 0.7 0.7)
					(thickness 0.15)
				)
				(justify left bottom mirror)
			)
		)
		(property "Datasheet" "https://www.bourns.com/docs/product-datasheets/cr.pdf"
			(at 0 0 180)
			(layer "F.Fab")
			(hide yes)
			(effects
				(font
					(size 1.27 1.27)
					(thickness 0.15)
				)
			)
		)
		(property "Description" "SMD Chip Resistor, 470 ohm, ± 1%, 62.5 mW, 0402 [1005 Metric], Thick Film, General Purpose"
			(at 0 0 180)
			(layer "F.Fab")
			(hide yes)
			(effects
				(font
					(size 1.27 1.27)
					(thickness 0.15)
				)
			)
		)
		(property "Author" "Antmicro"
			(at 444.26 256.4 0)
			(layer "B.Fab")
			(hide yes)
			(effects
				(font
					(size 1 1)
					(thickness 0.15)
				)
				(justify mirror)
			)
		)
		(property "License" "Apache-2.0"
			(at 444.26 256.4 0)
			(layer "B.Fab")
			(hide yes)
			(effects
				(font
					(size 1 1)
					(thickness 0.15)
				)
				(justify mirror)
			)
		)
		(property "MPN" "CR0402-FX-4700GLF"
			(at 444.26 256.4 0)
			(layer "B.Fab")
			(hide yes)
			(effects
				(font
					(size 1 1)
					(thickness 0.15)
				)
				(justify mirror)
			)
		)
		(property "Manufacturer" "Bourns"
			(at 444.26 256.4 0)
			(layer "B.Fab")
			(hide yes)
			(effects
				(font
					(size 1 1)
					(thickness 0.15)
				)
				(justify mirror)
			)
		)
		(property "Public" ""
			(at 444.26 256.4 0)
			(layer "B.Fab")
			(hide yes)
			(effects
				(font
					(size 1 1)
					(thickness 0.15)
				)
				(justify mirror)
			)
		)
		(property "Tolerance" "1%"
			(at 444.26 256.4 0)
			(layer "B.Fab")
			(hide yes)
			(effects
				(font
					(size 1 1)
					(thickness 0.15)
				)
				(justify mirror)
			)
		)
		(property "Val" "470R"
			(at 444.26 256.4 0)
			(layer "B.Fab")
			(hide yes)
			(effects
				(font
					(size 1 1)
					(thickness 0.15)
				)
				(justify mirror)
			)
		)
		(sheetname "/FPGA GPIO/")
		(sheetfile "fpga-gpio.kicad_sch")
		(attr smd)
		(fp_rect
			(start -0.925 0.47)
			(end 0.925 -0.47)
			(stroke
				(width 0.05)
				(type default)
			)
			(fill no)
			(layer "B.CrtYd")
		)
		(fp_rect
			(start -0.5 0.25)
			(end 0.5 -0.25)
			(stroke
				(width 0.15)
				(type solid)
			)
			(fill no)
			(layer "B.Fab")
		)
		(fp_text user "Author: Antmicro"
			(at -0.95 -4.169 0)
			(layer "B.Fab")
			(effects
				(font
					(size 0.7 0.7)
					(thickness 0.15)
				)
				(justify left bottom mirror)
			)
		)
		(fp_text user "License: Apache-2.0"
			(at -0.95 -5.169 0)
			(layer "B.Fab")
			(effects
				(font
					(size 0.7 0.7)
					(thickness 0.15)
				)
				(justify left bottom mirror)
			)
		)
		(fp_text user "${REFERENCE}"
			(at -0.95 -3.168 0)
			(layer "B.Fab")
			(effects
				(font
					(size 0.7 0.7)
					(thickness 0.15)
				)
				(justify left bottom mirror)
			)
		)
		(pad "1" smd roundrect
			(at -0.48 0 180)
			(size 0.59 0.64)
			(layers "B.Cu" "B.Mask" "B.Paste")
			(roundrect_rratio 0.25)
			(net 540 "Net-(Q5-D)")
			(pintype "passive")
		)
		(pad "2" smd roundrect
			(at 0.48 0 180)
			(size 0.59 0.64)
			(layers "B.Cu" "B.Mask" "B.Paste")
			(roundrect_rratio 0.25)
			(net 539 "Net-(D6-C_{B})")
			(pintype "passive")
		)
	)
	(footprint "antmicro-footprints:R_0402_1005Metric"
		(layer "B.Cu")
		(at 218.975 136.775 180)
		(descr "Resistor SMD 0402")
		(tags "resistor SMD 0402")
		(property "Reference" "R56"
			(at 0.75 -0.475 0)
			(layer "B.SilkS")
			(effects
				(font
					(size 0.7 0.7)
					(thickness 0.15)
				)
				(justify left bottom mirror)
			)
		)
		(property "Value" "R_0R_0402"
			(at -1.011843 -1.772047 0)
			(layer "B.Fab")
			(hide yes)
			(effects
				(font
					(size 0.7 0.7)
					(thickness 0.15)
				)
				(justify left bottom mirror)
			)
		)
		(property "Datasheet" "https://industrial.panasonic.com/cdbs/www-data/pdf/RDA0000/AOA0000C301.pdf"
			(at 0 0 180)
			(layer "F.Fab")
			(hide yes)
			(effects
				(font
					(size 1.27 1.27)
					(thickness 0.15)
				)
			)
		)
		(property "Description" "SMD Chip Resistor, Jumper, 0 ohm, 100 mW, 0402 [1005 Metric], Thick Film, General Purpose"
			(at 0 0 180)
			(layer "F.Fab")
			(hide yes)
			(effects
				(font
					(size 1.27 1.27)
					(thickness 0.15)
				)
			)
		)
		(property "Author" "Antmicro"
			(at 437.95 273.55 0)
			(layer "B.Fab")
			(hide yes)
			(effects
				(font
					(size 1 1)
					(thickness 0.15)
				)
				(justify mirror)
			)
		)
		(property "Current" "1A"
			(at 437.95 273.55 0)
			(layer "B.Fab")
			(hide yes)
			(effects
				(font
					(size 1 1)
					(thickness 0.15)
				)
				(justify mirror)
			)
		)
		(property "License" "Apache-2.0"
			(at 437.95 273.55 0)
			(layer "B.Fab")
			(hide yes)
			(effects
				(font
					(size 1 1)
					(thickness 0.15)
				)
				(justify mirror)
			)
		)
		(property "MPN" "ERJ2GE0R00X"
			(at 437.95 273.55 0)
			(layer "B.Fab")
			(hide yes)
			(effects
				(font
					(size 1 1)
					(thickness 0.15)
				)
				(justify mirror)
			)
		)
		(property "Manufacturer" "Panasonic"
			(at 437.95 273.55 0)
			(layer "B.Fab")
			(hide yes)
			(effects
				(font
					(size 1 1)
					(thickness 0.15)
				)
				(justify mirror)
			)
		)
		(property "Public" ""
			(at 437.95 273.55 0)
			(layer "B.Fab")
			(hide yes)
			(effects
				(font
					(size 1 1)
					(thickness 0.15)
				)
				(justify mirror)
			)
		)
		(property "Tolerance" "~"
			(at 437.95 273.55 0)
			(layer "B.Fab")
			(hide yes)
			(effects
				(font
					(size 1 1)
					(thickness 0.15)
				)
				(justify mirror)
			)
		)
		(property "Val" "0R"
			(at 437.95 273.55 0)
			(layer "B.Fab")
			(hide yes)
			(effects
				(font
					(size 1 1)
					(thickness 0.15)
				)
				(justify mirror)
			)
		)
		(sheetname "/Memory/")
		(sheetfile "memory.kicad_sch")
		(attr smd)
		(fp_rect
			(start -0.925 0.47)
			(end 0.925 -0.47)
			(stroke
				(width 0.05)
				(type default)
			)
			(fill no)
			(layer "B.CrtYd")
		)
		(fp_rect
			(start -0.5 0.25)
			(end 0.5 -0.25)
			(stroke
				(width 0.15)
				(type solid)
			)
			(fill no)
			(layer "B.Fab")
		)
		(fp_text user "Author: Antmicro"
			(at -0.95 -4.169 0)
			(layer "B.Fab")
			(effects
				(font
					(size 0.7 0.7)
					(thickness 0.15)
				)
				(justify left bottom mirror)
			)
		)
		(fp_text user "${REFERENCE}"
			(at -0.95 -3.168 0)
			(layer "B.Fab")
			(effects
				(font
					(size 0.7 0.7)
					(thickness 0.15)
				)
				(justify left bottom mirror)
			)
		)
		(fp_text user "License: Apache-2.0"
			(at -0.95 -5.169 0)
			(layer "B.Fab")
			(effects
				(font
					(size 0.7 0.7)
					(thickness 0.15)
				)
				(justify left bottom mirror)
			)
		)
		(pad "1" smd roundrect
			(at -0.48 0 180)
			(size 0.59 0.64)
			(layers "B.Cu" "B.Mask" "B.Paste")
			(roundrect_rratio 0.25)
			(net 518 "Net-(R56-Pad1)")
			(pintype "passive")
		)
		(pad "2" smd roundrect
			(at 0.48 0 180)
			(size 0.59 0.64)
			(layers "B.Cu" "B.Mask" "B.Paste")
			(roundrect_rratio 0.25)
			(net 519 "SD_VDD_AUX")
			(pintype "passive")
		)
	)
	(footprint "antmicro-footprints:C_0402_1005Metric"
		(layer "B.Cu")
		(at 222.35 120.03 180)
		(descr "Capacitor SMD 0402")
		(tags "capacitor SMD 0402")
		(property "Reference" "C45"
			(at -1.05 1.33 0)
			(layer "B.SilkS")
			(effects
				(font
					(size 0.7 0.7)
					(thickness 0.15)
				)
				(justify left bottom mirror)
			)
		)
		(property "Value" "C_100n_0402"
			(at -1.022927 -2.155213 0)
			(layer "B.Fab")
			(hide yes)
			(effects
				(font
					(size 0.7 0.7)
					(thickness 0.15)
				)
				(justify left bottom mirror)
			)
		)
		(property "Datasheet" "https://www.murata.com/products/productdetail?partno=GRM155R61H104KE14%23"
			(at 0 0 180)
			(layer "F.Fab")
			(hide yes)
			(effects
				(font
					(size 1.27 1.27)
					(thickness 0.15)
				)
			)
		)
		(property "Description" "SMD Multilayer Ceramic Capacitor, 0.1 µF, 50 V, 0402 [1005 Metric], ± 10%, X5R, GRM Series"
			(at 0 0 180)
			(layer "F.Fab")
			(hide yes)
			(effects
				(font
					(size 1.27 1.27)
					(thickness 0.15)
				)
			)
		)
		(property "Author" "Antmicro"
			(at 444.7 240.06 0)
			(layer "B.Fab")
			(hide yes)
			(effects
				(font
					(size 1 1)
					(thickness 0.15)
				)
				(justify mirror)
			)
		)
		(property "Dielectric" "X5R"
			(at 444.7 240.06 0)
			(layer "B.Fab")
			(hide yes)
			(effects
				(font
					(size 1 1)
					(thickness 0.15)
				)
				(justify mirror)
			)
		)
		(property "License" "Apache-2.0"
			(at 444.7 240.06 0)
			(layer "B.Fab")
			(hide yes)
			(effects
				(font
					(size 1 1)
					(thickness 0.15)
				)
				(justify mirror)
			)
		)
		(property "MPN" "GRM155R61H104KE14D"
			(at 444.7 240.06 0)
			(layer "B.Fab")
			(hide yes)
			(effects
				(font
					(size 1 1)
					(thickness 0.15)
				)
				(justify mirror)
			)
		)
		(property "Manufacturer" "Murata"
			(at 444.7 240.06 0)
			(layer "B.Fab")
			(hide yes)
			(effects
				(font
					(size 1 1)
					(thickness 0.15)
				)
				(justify mirror)
			)
		)
		(property "Public" ""
			(at 444.7 240.06 0)
			(layer "B.Fab")
			(hide yes)
			(effects
				(font
					(size 1 1)
					(thickness 0.15)
				)
				(justify mirror)
			)
		)
		(property "Val" "100n"
			(at 444.7 240.06 0)
			(layer "B.Fab")
			(hide yes)
			(effects
				(font
					(size 1 1)
					(thickness 0.15)
				)
				(justify mirror)
			)
		)
		(property "Voltage" "50V"
			(at 444.7 240.06 0)
			(layer "B.Fab")
			(hide yes)
			(effects
				(font
					(size 1 1)
					(thickness 0.15)
				)
				(justify mirror)
			)
		)
		(sheetname "/FPGA GPIO/")
		(sheetfile "fpga-gpio.kicad_sch")
		(attr smd)
		(fp_rect
			(start -0.925 0.47)
			(end 0.925 -0.47)
			(stroke
				(width 0.05)
				(type default)
			)
			(fill no)
			(layer "B.CrtYd")
		)
		(fp_line
			(start 0.504 0.25)
			(end 0.504 -0.248)
			(stroke
				(width 0.15)
				(type solid)
			)
			(layer "B.Fab")
		)
		(fp_line
			(start 0.504 -0.248)
			(end -0.494 -0.248)
			(stroke
				(width 0.15)
				(type solid)
			)
			(layer "B.Fab")
		)
		(fp_line
			(start -0.494 0.25)
			(end 0.504 0.25)
			(stroke
				(width 0.15)
				(type solid)
			)
			(layer "B.Fab")
		)
		(fp_line
			(start -0.494 -0.248)
			(end -0.494 0.25)
			(stroke
				(width 0.15)
				(type solid)
			)
			(layer "B.Fab")
		)
		(fp_text user "License: Apache-2.0"
			(at -0.939 -5.799 0)
			(layer "B.Fab")
			(effects
				(font
					(size 0.7 0.7)
					(thickness 0.15)
				)
				(justify left bottom mirror)
			)
		)
		(fp_text user "${REFERENCE}"
			(at -0.939 -4.599 0)
			(layer "B.Fab")
			(effects
				(font
					(size 0.7 0.7)
					(thickness 0.15)
				)
				(justify left bottom mirror)
			)
		)
		(fp_text user "Author: Antmicro"
			(at -0.939 -3.399 0)
			(layer "B.Fab")
			(effects
				(font
					(size 0.7 0.7)
					(thickness 0.15)
				)
				(justify left bottom mirror)
			)
		)
		(pad "1" smd roundrect
			(at -0.48 0 180)
			(size 0.59 0.64)
			(layers "B.Cu" "B.Mask" "B.Paste")
			(roundrect_rratio 0.25)
			(net 50 "+3V3")
			(pintype "passive")
		)
		(pad "2" smd roundrect
			(at 0.48 0 180)
			(size 0.59 0.64)
			(layers "B.Cu" "B.Mask" "B.Paste")
			(roundrect_rratio 0.25)
			(net 417 "GND")
			(pintype "passive")
		)
	)
	(footprint "antmicro-footprints:R_0402_1005Metric"
		(layer "B.Cu")
		(at 219.92 124.82 180)
		(descr "Resistor SMD 0402")
		(tags "resistor SMD 0402")
		(property "Reference" "R103"
			(at -3.75 -0.34 0)
			(layer "B.SilkS")
			(effects
				(font
					(size 0.7 0.7)
					(thickness 0.15)
				)
				(justify left bottom mirror)
			)
		)
		(property "Value" "R_2k2_0402"
			(at -1.011843 -1.772047 0)
			(layer "B.Fab")
			(hide yes)
			(effects
				(font
					(size 0.7 0.7)
					(thickness 0.15)
				)
				(justify left bottom mirror)
			)
		)
		(property "Datasheet" "https://www.bourns.com/docs/product-datasheets/cr.pdf"
			(at 0 0 180)
			(layer "F.Fab")
			(hide yes)
			(effects
				(font
					(size 1.27 1.27)
					(thickness 0.15)
				)
			)
		)
		(property "Description" "SMD Chip Resistor, 2.2 kohm, ± 1%, 62.5 mW, 0402 [1005 Metric], Thick Film, General Purpose"
			(at 0 0 180)
			(layer "F.Fab")
			(hide yes)
			(effects
				(font
					(size 1.27 1.27)
					(thickness 0.15)
				)
			)
		)
		(property "Author" "Antmicro"
			(at 439.84 249.64 0)
			(layer "B.Fab")
			(hide yes)
			(effects
				(font
					(size 1 1)
					(thickness 0.15)
				)
				(justify mirror)
			)
		)
		(property "License" "Apache-2.0"
			(at 439.84 249.64 0)
			(layer "B.Fab")
			(hide yes)
			(effects
				(font
					(size 1 1)
					(thickness 0.15)
				)
				(justify mirror)
			)
		)
		(property "MPN" "CR0402-FX-2201GLF"
			(at 439.84 249.64 0)
			(layer "B.Fab")
			(hide yes)
			(effects
				(font
					(size 1 1)
					(thickness 0.15)
				)
				(justify mirror)
			)
		)
		(property "Manufacturer" "Bourns"
			(at 439.84 249.64 0)
			(layer "B.Fab")
			(hide yes)
			(effects
				(font
					(size 1 1)
					(thickness 0.15)
				)
				(justify mirror)
			)
		)
		(property "Public" ""
			(at 439.84 249.64 0)
			(layer "B.Fab")
			(hide yes)
			(effects
				(font
					(size 1 1)
					(thickness 0.15)
				)
				(justify mirror)
			)
		)
		(property "Tolerance" "1%"
			(at 439.84 249.64 0)
			(layer "B.Fab")
			(hide yes)
			(effects
				(font
					(size 1 1)
					(thickness 0.15)
				)
				(justify mirror)
			)
		)
		(property "Val" "2k2"
			(at 439.84 249.64 0)
			(layer "B.Fab")
			(hide yes)
			(effects
				(font
					(size 1 1)
					(thickness 0.15)
				)
				(justify mirror)
			)
		)
		(sheetname "/Ethernet/")
		(sheetfile "ethernet.kicad_sch")
		(attr smd)
		(fp_rect
			(start -0.925 0.47)
			(end 0.925 -0.47)
			(stroke
				(width 0.05)
				(type default)
			)
			(fill no)
			(layer "B.CrtYd")
		)
		(fp_rect
			(start -0.5 0.25)
			(end 0.5 -0.25)
			(stroke
				(width 0.15)
				(type solid)
			)
			(fill no)
			(layer "B.Fab")
		)
		(fp_text user "Author: Antmicro"
			(at -0.95 -4.169 0)
			(layer "B.Fab")
			(effects
				(font
					(size 0.7 0.7)
					(thickness 0.15)
				)
				(justify left bottom mirror)
			)
		)
		(fp_text user "${REFERENCE}"
			(at -0.95 -3.168 0)
			(layer "B.Fab")
			(effects
				(font
					(size 0.7 0.7)
					(thickness 0.15)
				)
				(justify left bottom mirror)
			)
		)
		(fp_text user "License: Apache-2.0"
			(at -0.95 -5.169 0)
			(layer "B.Fab")
			(effects
				(font
					(size 0.7 0.7)
					(thickness 0.15)
				)
				(justify left bottom mirror)
			)
		)
		(pad "1" smd roundrect
			(at -0.48 0 180)
			(size 0.59 0.64)
			(layers "B.Cu" "B.Mask" "B.Paste")
			(roundrect_rratio 0.25)
			(net 417 "GND")
			(pintype "passive")
		)
		(pad "2" smd roundrect
			(at 0.48 0 180)
			(size 0.59 0.64)
			(layers "B.Cu" "B.Mask" "B.Paste")
			(roundrect_rratio 0.25)
			(net 617 "/Ethernet/LED0")
			(pintype "passive")
		)
	)
	(footprint "antmicro-footprints:C_0402_1005Metric"
		(layer "B.Cu")
		(at 193.3 134.27)
		(descr "Capacitor SMD 0402")
		(tags "capacitor SMD 0402")
		(property "Reference" "C51"
			(at -2.85 -0.495 0)
			(layer "B.SilkS")
			(effects
				(font
					(size 0.7 0.7)
					(thickness 0.15)
				)
				(justify right bottom mirror)
			)
		)
		(property "Value" "C_1n_0402"
			(at -1.022927 -2.155213 0)
			(layer "B.Fab")
			(hide yes)
			(effects
				(font
					(size 0.7 0.7)
					(thickness 0.15)
				)
				(justify right bottom mirror)
			)
		)
		(property "Datasheet" "https://www.murata.com/products/productdetail?partno=GRM1555C1H102JA01%23"
			(at 0 0 0)
			(layer "F.Fab")
			(hide yes)
			(effects
				(font
					(size 1.27 1.27)
					(thickness 0.15)
				)
			)
		)
		(property "Description" "SMD Multilayer Ceramic Capacitor, 1000 pF, 50 V, 0402 [1005 Metric], ± 5%, C0G / NP0, GRM Series"
			(at 0 0 0)
			(layer "F.Fab")
			(hide yes)
			(effects
				(font
					(size 1.27 1.27)
					(thickness 0.15)
				)
			)
		)
		(property "Author" "Antmicro"
			(at 0 0 0)
			(layer "B.Fab")
			(hide yes)
			(effects
				(font
					(size 1 1)
					(thickness 0.15)
				)
				(justify mirror)
			)
		)
		(property "Dielectric" "C0G"
			(at 0 0 0)
			(layer "B.Fab")
			(hide yes)
			(effects
				(font
					(size 1 1)
					(thickness 0.15)
				)
				(justify mirror)
			)
		)
		(property "License" "Apache-2.0"
			(at 0 0 0)
			(layer "B.Fab")
			(hide yes)
			(effects
				(font
					(size 1 1)
					(thickness 0.15)
				)
				(justify mirror)
			)
		)
		(property "MPN" "GRM1555C1H102JA01D"
			(at 0 0 0)
			(layer "B.Fab")
			(hide yes)
			(effects
				(font
					(size 1 1)
					(thickness 0.15)
				)
				(justify mirror)
			)
		)
		(property "Manufacturer" "Murata"
			(at 0 0 0)
			(layer "B.Fab")
			(hide yes)
			(effects
				(font
					(size 1 1)
					(thickness 0.15)
				)
				(justify mirror)
			)
		)
		(property "Public" ""
			(at 0 0 0)
			(layer "B.Fab")
			(hide yes)
			(effects
				(font
					(size 1 1)
					(thickness 0.15)
				)
				(justify mirror)
			)
		)
		(property "Val" "1n"
			(at 0 0 0)
			(layer "B.Fab")
			(hide yes)
			(effects
				(font
					(size 1 1)
					(thickness 0.15)
				)
				(justify mirror)
			)
		)
		(property "Voltage" "50V"
			(at 0 0 0)
			(layer "B.Fab")
			(hide yes)
			(effects
				(font
					(size 1 1)
					(thickness 0.15)
				)
				(justify mirror)
			)
		)
		(sheetname "/FPGA Supply/")
		(sheetfile "fpga-supply.kicad_sch")
		(attr smd)
		(fp_rect
			(start -0.925 0.47)
			(end 0.925 -0.47)
			(stroke
				(width 0.05)
				(type default)
			)
			(fill no)
			(layer "B.CrtYd")
		)
		(fp_line
			(start -0.494 -0.248)
			(end -0.494 0.25)
			(stroke
				(width 0.15)
				(type solid)
			)
			(layer "B.Fab")
		)
		(fp_line
			(start -0.494 0.25)
			(end 0.504 0.25)
			(stroke
				(width 0.15)
				(type solid)
			)
			(layer "B.Fab")
		)
		(fp_line
			(start 0.504 -0.248)
			(end -0.494 -0.248)
			(stroke
				(width 0.15)
				(type solid)
			)
			(layer "B.Fab")
		)
		(fp_line
			(start 0.504 0.25)
			(end 0.504 -0.248)
			(stroke
				(width 0.15)
				(type solid)
			)
			(layer "B.Fab")
		)
		(fp_text user "Author: Antmicro"
			(at -0.939 -3.399 180)
			(layer "B.Fab")
			(effects
				(font
					(size 0.7 0.7)
					(thickness 0.15)
				)
				(justify left bottom mirror)
			)
		)
		(fp_text user "${REFERENCE}"
			(at -0.939 -4.599 180)
			(layer "B.Fab")
			(effects
				(font
					(size 0.7 0.7)
					(thickness 0.15)
				)
				(justify left bottom mirror)
			)
		)
		(fp_text user "License: Apache-2.0"
			(at -0.939 -5.799 180)
			(layer "B.Fab")
			(effects
				(font
					(size 0.7 0.7)
					(thickness 0.15)
				)
				(justify left bottom mirror)
			)
		)
		(pad "1" smd roundrect
			(at -0.48 0)
			(size 0.59 0.64)
			(layers "B.Cu" "B.Mask" "B.Paste")
			(roundrect_rratio 0.25)
			(net 417 "GND")
			(pintype "passive")
		)
		(pad "2" smd roundrect
			(at 0.48 0)
			(size 0.59 0.64)
			(layers "B.Cu" "B.Mask" "B.Paste")
			(roundrect_rratio 0.25)
			(net 48 "+1V8")
			(pintype "passive")
		)
	)
)
